# BASEBOARD_FAB2 (Tioga Pass) — schematic netlist excerpt (pin names and nets, part order shuffled) for the footprints in the layout excerpt that follows; sources: Cadence DE-HDL packaged netlist, KiCad conversion of Wiwynn_Tioga_Pass_MB.brd

R7F36  RES  2.26K 1.0% CHIP  pkg 0402  page 215 : A = P3V3_STBY ; B = PWRGD_PVDDQ_ABC
C4E18  CAP  0.220UF 16V 10% X7R  pkg 0402  page 214 : A = VR_PVCCIO_CPU1_PH1_BOOT ; B = VR_PVCCIO_CPU1_PH1_PHASE
L4D2  IND-120NH-30-GP  pkg DISCRET-GB2  page 203 : S = VR_PVCCIN_CPU0_PHASE3 ; F = PVCCIN_CPU0

(kicad_pcb
	(version 20260206)
	(generator "pcbnew")
	(generator_version "10.0")
	(general
		(thickness 1.6)
		(legacy_teardrops no)
	)
	(paper "A4")
	(title_block
		(title "Wiwynn_Tioga_Pass_MB.brd")
		(comment 1 "Tioga Pass / footprints 1615-1617 of 4770")
	)
	(layers
		(0 "F.Cu" signal "TOP")
		(4 "In1.Cu" signal "L2GND")
		(6 "In2.Cu" signal "L3")
		(8 "In3.Cu" signal "L4GND")
		(10 "In4.Cu" signal "L5")
		(12 "In5.Cu" signal "L6GND")
		(14 "In6.Cu" signal "L7VCC")
		(16 "In7.Cu" signal "L8VCC")
		(18 "In8.Cu" signal "L9GND")
		(20 "In9.Cu" signal "L10")
		(22 "In10.Cu" signal "L11GND")
		(24 "In11.Cu" signal "L12")
		(26 "In12.Cu" signal "L13GND")
		(2 "B.Cu" signal "BOTTOM")
		(9 "F.Adhes" user "F.Adhesive")
		(11 "B.Adhes" user "B.Adhesive")
		(13 "F.Paste" user "Package Geometry/Pastemask Top")
		(15 "B.Paste" user "Package Geometry/Pastemask Bottom")
		(5 "F.SilkS" user "Ref Des/Silkscreen Top")
		(7 "B.SilkS" user "Ref Des/Silkscreen Bottom")
		(1 "F.Mask" user "Board Geometry/Soldermask Top")
		(3 "B.Mask" user "Board Geometry/Soldermask Bottom")
		(17 "Dwgs.User" user "User.Drawings")
		(19 "Cmts.User" user "User.Comments")
		(21 "Eco1.User" user "User.Eco1")
		(23 "Eco2.User" user "User.Eco2")
		(25 "Edge.Cuts" user "Board Geometry/Outline")
		(27 "Margin" user)
		(31 "F.CrtYd" user "Package Geometry/Place Bound Top")
		(29 "B.CrtYd" user "Package Geometry/Place Bound Bottom")
		(35 "F.Fab" user "Ref Des/Assembly Top")
		(33 "B.Fab" user "Ref Des/Assembly Bottom")
	)
	(footprint ""
		(layer "F.Cu")
		(at 205.036928 -73.287382)
		(property "Reference" "L4D2"
			(at 3.378708 -4.251706 0)
			(unlocked yes)
			(layer "F.SilkS")
			(effects
				(font
					(size 0.4064 0.254)
					(thickness 0.1524)
				)
			)
		)
		(property "Value" ""
			(at 0 0 0)
			(layer "F.Fab")
			(effects
				(font
					(size 1.27 1.27)
				)
			)
		)
		(duplicate_pad_numbers_are_jumpers no)
		(fp_line
			(start -1.1303 -3.199892)
			(end 8.3693 -3.199892)
			(stroke
				(width 0.1524)
				(type default)
			)
			(layer "F.SilkS")
		)
		(fp_line
			(start -1.1303 -1.6637)
			(end -1.1303 -3.199892)
			(stroke
				(width 0.1524)
				(type default)
			)
			(layer "F.SilkS")
		)
		(fp_line
			(start -1.1303 3.199892)
			(end -1.1303 1.6637)
			(stroke
				(width 0.1524)
				(type default)
			)
			(layer "F.SilkS")
		)
		(fp_line
			(start 8.3693 -3.199892)
			(end 8.3693 -1.6637)
			(stroke
				(width 0.1524)
				(type default)
			)
			(layer "F.SilkS")
		)
		(fp_line
			(start 8.3693 1.6637)
			(end 8.3693 3.199892)
			(stroke
				(width 0.1524)
				(type default)
			)
			(layer "F.SilkS")
		)
		(fp_line
			(start 8.3693 3.199892)
			(end -1.1303 3.199892)
			(stroke
				(width 0.1524)
				(type default)
			)
			(layer "F.SilkS")
		)
		(fp_rect
			(start -1.1303 3.199892)
			(end 8.3693 -3.199892)
			(stroke
				(width 0)
				(type default)
			)
			(fill no)
			(layer "F.CrtYd")
		)
		(fp_line
			(start -1.1303 -3.199892)
			(end 8.3693 -3.199892)
			(stroke
				(width 0.1)
				(type default)
			)
			(layer "F.Fab")
		)
		(fp_line
			(start -1.1303 3.199892)
			(end -1.1303 -3.199892)
			(stroke
				(width 0.1)
				(type default)
			)
			(layer "F.Fab")
		)
		(fp_line
			(start 8.3693 -3.199892)
			(end 8.3693 3.199892)
			(stroke
				(width 0.1)
				(type default)
			)
			(layer "F.Fab")
		)
		(fp_line
			(start 8.3693 3.199892)
			(end -1.1303 3.199892)
			(stroke
				(width 0.1)
				(type default)
			)
			(layer "F.Fab")
		)
		(pad "1" smd rect
			(at 0 0)
			(size 3.683 2.667)
			(layers "F.Cu" "F.Mask" "F.Paste")
			(net "VR_PVCCIN_CPU0_PHASE3")
		)
		(pad "2" smd rect
			(at 7.239 0)
			(size 3.683 2.667)
			(layers "F.Cu" "F.Mask" "F.Paste")
			(net "PVCCIN_CPU0")
		)
	)
	(footprint ""
		(layer "F.Cu")
		(at 182.3466 -52.5907 -90)
		(property "Reference" "C4E18"
			(at 0 0 270)
			(layer "F.SilkS")
			(hide yes)
			(effects
				(font
					(size 1.27 1.27)
				)
			)
		)
		(property "Value" ""
			(at 0 0 270)
			(layer "F.Fab")
			(effects
				(font
					(size 1.27 1.27)
				)
			)
		)
		(duplicate_pad_numbers_are_jumpers no)
		(fp_poly
			(pts
				(xy 0.3048 -0.1016) (xy 0.3048 0.9906) (xy -0.3048 0.9906) (xy -0.3048 -0.1016)
			)
			(stroke
				(width 0)
				(type default)
			)
			(fill no)
			(layer "F.CrtYd")
		)
		(fp_line
			(start -0.3048 0.9906)
			(end 0.3048 0.9906)
			(stroke
				(width 0.1)
				(type default)
			)
			(layer "F.Fab")
		)
		(fp_line
			(start 0.3048 0.9906)
			(end 0.3048 -0.1016)
			(stroke
				(width 0.1)
				(type default)
			)
			(layer "F.Fab")
		)
		(fp_line
			(start -0.3048 -0.1016)
			(end -0.3048 0.9906)
			(stroke
				(width 0.1)
				(type default)
			)
			(layer "F.Fab")
		)
		(fp_line
			(start 0.3048 -0.1016)
			(end -0.3048 -0.1016)
			(stroke
				(width 0.1)
				(type default)
			)
			(layer "F.Fab")
		)
		(pad "1" smd rect
			(at 0 0 270)
			(size 0.508 0.508)
			(layers "F.Cu" "F.Mask" "F.Paste")
			(net "VR_PVCCIO_CPU1_PH1_BOOT")
		)
		(pad "2" smd rect
			(at 0 0.889 270)
			(size 0.508 0.508)
			(layers "F.Cu" "F.Mask" "F.Paste")
			(net "VR_PVCCIO_CPU1_PH1_PHASE")
		)
		(zone
			(layer "F.Cu")
			(hatch none 0.5)
			(connect_pads
				(clearance 0)
			)
			(min_thickness 0.25)
			(keepout
				(tracks not_allowed)
				(vias allowed)
				(pads allowed)
				(copperpour not_allowed)
				(footprints allowed)
			)
			(placement
				(enabled no)
				(sheetname "")
			)
			(fill
				(thermal_gap 0.5)
				(thermal_bridge_width 0.5)
				(island_removal_mode 0)
			)
			(polygon
				(pts
					(xy 181.7116 -52.8447) (xy 181.7116 -52.3367) (xy 182.0926 -52.3367) (xy 182.0926 -52.8447)
				)
			)
		)
		(zone
			(layer "F.Cu")
			(hatch none 0.5)
			(connect_pads
				(clearance 0)
			)
			(min_thickness 0.25)
			(keepout
				(tracks allowed)
				(vias not_allowed)
				(pads allowed)
				(copperpour not_allowed)
				(footprints allowed)
			)
			(placement
				(enabled no)
				(sheetname "")
			)
			(fill
				(thermal_gap 0.5)
				(thermal_bridge_width 0.5)
				(island_removal_mode 0)
			)
			(polygon
				(pts
					(xy 182.0926 -52.8447) (xy 182.0926 -52.3367) (xy 181.7116 -52.3367) (xy 181.7116 -52.8447)
				)
			)
		)
	)
	(footprint ""
		(layer "F.Cu")
		(at 336.9564 -20.5486)
		(property "Reference" "R7F36"
			(at -0.8382 -0.67818 0)
			(unlocked yes)
			(layer "F.SilkS")
			(effects
				(font
					(size 0.4064 0.254)
					(thickness 0.1524)
				)
				(justify left)
			)
		)
		(property "Value" ""
			(at 0 0 0)
			(layer "F.Fab")
			(effects
				(font
					(size 1.27 1.27)
				)
			)
		)
		(duplicate_pad_numbers_are_jumpers no)
		(fp_poly
			(pts
				(xy -0.2794 -0.1016) (xy 0.2794 -0.1016) (xy 0.2794 0.9906) (xy -0.2794 0.9906)
			)
			(stroke
				(width 0)
				(type default)
			)
			(fill no)
			(layer "F.CrtYd")
		)
		(fp_line
			(start -0.2794 -0.1016)
			(end -0.2794 0.9906)
			(stroke
				(width 0.1)
				(type default)
			)
			(layer "F.Fab")
		)
		(fp_line
			(start -0.2794 0.9906)
			(end 0.2794 0.9906)
			(stroke
				(width 0.1)
				(type default)
			)
			(layer "F.Fab")
		)
		(fp_line
			(start 0.2794 -0.1016)
			(end -0.2794 -0.1016)
			(stroke
				(width 0.1)
				(type default)
			)
			(layer "F.Fab")
		)
		(fp_line
			(start 0.2794 0.9906)
			(end 0.2794 -0.1016)
			(stroke
				(width 0.1)
				(type default)
			)
			(layer "F.Fab")
		)
		(pad "1" smd rect
			(at 0 0)
			(size 0.508 0.508)
			(layers "F.Cu" "F.Mask" "F.Paste")
			(net "P3V3_STBY")
		)
		(pad "2" smd rect
			(at 0 0.889)
			(size 0.508 0.508)
			(layers "F.Cu" "F.Mask" "F.Paste")
			(net "PWRGD_PVDDQ_ABC")
		)
		(zone
			(layer "F.Cu")
			(hatch none 0.5)
			(connect_pads
				(clearance 0)
			)
			(min_thickness 0.25)
			(keepout
				(tracks allowed)
				(vias not_allowed)
				(pads allowed)
				(copperpour not_allowed)
				(footprints allowed)
			)
			(placement
				(enabled no)
				(sheetname "")
			)
			(fill
				(thermal_gap 0.5)
				(thermal_bridge_width 0.5)
				(island_removal_mode 0)
			)
			(polygon
				(pts
					(xy 336.7024 -20.2946) (xy 337.2104 -20.2946) (xy 337.2104 -19.9136) (xy 336.7024 -19.9136)
				)
			)
		)
		(zone
			(layer "F.Cu")
			(hatch none 0.5)
			(connect_pads
				(clearance 0)
			)
			(min_thickness 0.25)
			(keepout
				(tracks not_allowed)
				(vias allowed)
				(pads allowed)
				(copperpour not_allowed)
				(footprints allowed)
			)
			(placement
				(enabled no)
				(sheetname "")
			)
			(fill
				(thermal_gap 0.5)
				(thermal_bridge_width 0.5)
				(island_removal_mode 0)
			)
			(polygon
				(pts
					(xy 336.7024 -19.9136) (xy 337.2104 -19.9136) (xy 337.2104 -20.2946) (xy 336.7024 -20.2946)
				)
			)
		)
	)
)
